# T6G (Grand Teton) — schematic netlist excerpt (pin names and nets, part order shuffled) for the footprints in the layout excerpt that follows; sources: Cadence DE-HDL packaged netlist, KiCad conversion of 04192023_DAF0TMB3IC0_F0TG_MB_C_brd_V02_OCP.brd

R223  Q_RES  0 5% CHIP  pkg 0402LF  page 82 : A = FM_CPU0_SP5R4 ; B = CPU0_SP5R4
R6174  Q_RES  1K 1% EMPTY  pkg 0402LF  page 112 : A = FM_P2E_BUF2_EQA0 ; B = GND

(kicad_pcb
	(version 20260206)
	(generator "pcbnew")
	(generator_version "10.0")
	(general
		(thickness 1.6)
		(legacy_teardrops no)
	)
	(paper "A4")
	(title_block
		(title "04192023_DAF0TMB3IC0_F0TG_MB_C_brd_V02_OCP.brd")
		(comment 1 "Grand Teton / footprints 4096-4097 of 8354")
	)
	(layers
		(0 "F.Cu" signal "TOP")
		(4 "In1.Cu" signal "GND")
		(6 "In2.Cu" signal "IN1")
		(8 "In3.Cu" signal "GND1")
		(10 "In4.Cu" signal "IN2")
		(12 "In5.Cu" signal "GND2")
		(14 "In6.Cu" signal "IN3")
		(16 "In7.Cu" signal "GND3")
		(18 "In8.Cu" signal "VCC")
		(20 "In9.Cu" signal "VCC1")
		(22 "In10.Cu" signal "GND4")
		(24 "In11.Cu" signal "IN4")
		(26 "In12.Cu" signal "GND5")
		(28 "In13.Cu" signal "IN5")
		(30 "In14.Cu" signal "GND6")
		(32 "In15.Cu" signal "IN6")
		(34 "In16.Cu" signal "GND7")
		(2 "B.Cu" signal "BOTTOM")
		(9 "F.Adhes" user "F.Adhesive")
		(11 "B.Adhes" user "B.Adhesive")
		(13 "F.Paste" user "Package Geometry/Pastemask Top")
		(15 "B.Paste" user "Package Geometry/Pastemask Bottom")
		(5 "F.SilkS" user "Ref Des/Silkscreen Top")
		(7 "B.SilkS" user "Ref Des/Silkscreen Bottom")
		(1 "F.Mask" user "Board Geometry/Soldermask Top")
		(3 "B.Mask" user "Board Geometry/Soldermask Bottom")
		(17 "Dwgs.User" user "User.Drawings")
		(19 "Cmts.User" user "User.Comments")
		(21 "Eco1.User" user "User.Eco1")
		(23 "Eco2.User" user "User.Eco2")
		(25 "Edge.Cuts" user "Board Geometry/Outline")
		(27 "Margin" user)
		(31 "F.CrtYd" user "Package Geometry/Place Bound Top")
		(29 "B.CrtYd" user "Package Geometry/Place Bound Bottom")
		(35 "F.Fab" user "Ref Des/Assembly Top")
		(33 "B.Fab" user "Ref Des/Assembly Bottom")
	)
	(footprint ""
		(layer "F.Cu")
		(at 11.665458 -422.551098 180)
		(property "Reference" "R6174"
			(at 0 0 180)
			(layer "F.SilkS")
			(hide yes)
			(effects
				(font
					(size 1.27 1.27)
				)
			)
		)
		(property "Value" ""
			(at 0 0 180)
			(layer "F.Fab")
			(effects
				(font
					(size 1.27 1.27)
				)
			)
		)
		(duplicate_pad_numbers_are_jumpers no)
		(fp_line
			(start 0.7874 0.4064)
			(end -0.7874 0.4064)
			(stroke
				(width 0.1524)
				(type default)
			)
			(layer "F.SilkS")
		)
		(fp_line
			(start 0.7874 -0.4064)
			(end 0.7874 0.4064)
			(stroke
				(width 0.1524)
				(type default)
			)
			(layer "F.SilkS")
		)
		(fp_line
			(start -0.7874 0.4064)
			(end -0.7874 -0.4064)
			(stroke
				(width 0.1524)
				(type default)
			)
			(layer "F.SilkS")
		)
		(fp_line
			(start -0.7874 -0.4064)
			(end 0.7874 -0.4064)
			(stroke
				(width 0.1524)
				(type default)
			)
			(layer "F.SilkS")
		)
		(fp_line
			(start 0.67945 0.3048)
			(end 0.120396 0.3048)
			(stroke
				(width 0.1)
				(type default)
			)
			(layer "F.Fab")
		)
		(fp_line
			(start 0.67945 -0.3048)
			(end 0.67945 0.3048)
			(stroke
				(width 0.1)
				(type default)
			)
			(layer "F.Fab")
		)
		(fp_line
			(start 0.12065 -0.2794)
			(end 0.12065 -0.3048)
			(stroke
				(width 0.1)
				(type default)
			)
			(layer "F.Fab")
		)
		(fp_line
			(start 0.12065 -0.3048)
			(end 0.67945 -0.3048)
			(stroke
				(width 0.1)
				(type default)
			)
			(layer "F.Fab")
		)
		(fp_line
			(start 0.120396 0.3048)
			(end 0.120396 0.2794)
			(stroke
				(width 0.1)
				(type default)
			)
			(layer "F.Fab")
		)
		(fp_line
			(start 0.120396 0.2794)
			(end -0.12065 0.2794)
			(stroke
				(width 0.1)
				(type default)
			)
			(layer "F.Fab")
		)
		(fp_line
			(start -0.12065 0.3048)
			(end -0.67945 0.3048)
			(stroke
				(width 0.1)
				(type default)
			)
			(layer "F.Fab")
		)
		(fp_line
			(start -0.12065 0.2794)
			(end -0.12065 0.3048)
			(stroke
				(width 0.1)
				(type default)
			)
			(layer "F.Fab")
		)
		(fp_line
			(start -0.12065 -0.2794)
			(end 0.12065 -0.2794)
			(stroke
				(width 0.1)
				(type default)
			)
			(layer "F.Fab")
		)
		(fp_line
			(start -0.12065 -0.305054)
			(end -0.12065 -0.2794)
			(stroke
				(width 0.1)
				(type default)
			)
			(layer "F.Fab")
		)
		(fp_line
			(start -0.67945 0.3048)
			(end -0.67945 -0.305054)
			(stroke
				(width 0.1)
				(type default)
			)
			(layer "F.Fab")
		)
		(fp_line
			(start -0.67945 -0.305054)
			(end -0.12065 -0.305054)
			(stroke
				(width 0.1)
				(type default)
			)
			(layer "F.Fab")
		)
		(pad "1" smd circle
			(at -0.40005 0 180)
			(size 0 0)
			(layers "F.Cu" "F.Mask" "F.Paste")
			(net "FM_P2E_BUF2_EQA0")
		)
		(pad "2" smd circle
			(at 0.40005 0 180)
			(size 0 0)
			(layers "F.Cu" "F.Mask" "F.Paste")
			(net "GND")
		)
	)
	(footprint ""
		(layer "F.Cu")
		(at 193.929 -100.294948 -90)
		(property "Reference" "R223"
			(at 0 0 270)
			(layer "F.SilkS")
			(hide yes)
			(effects
				(font
					(size 1.27 1.27)
				)
			)
		)
		(property "Value" ""
			(at 0 0 270)
			(layer "F.Fab")
			(effects
				(font
					(size 1.27 1.27)
				)
			)
		)
		(duplicate_pad_numbers_are_jumpers no)
		(fp_line
			(start -0.7874 0.4064)
			(end -0.7874 -0.4064)
			(stroke
				(width 0.1524)
				(type default)
			)
			(layer "F.SilkS")
		)
		(fp_line
			(start 0.7874 0.4064)
			(end -0.7874 0.4064)
			(stroke
				(width 0.1524)
				(type default)
			)
			(layer "F.SilkS")
		)
		(fp_line
			(start -0.7874 -0.4064)
			(end 0.7874 -0.4064)
			(stroke
				(width 0.1524)
				(type default)
			)
			(layer "F.SilkS")
		)
		(fp_line
			(start 0.7874 -0.4064)
			(end 0.7874 0.4064)
			(stroke
				(width 0.1524)
				(type default)
			)
			(layer "F.SilkS")
		)
		(fp_line
			(start -0.67945 0.3048)
			(end -0.67945 -0.305054)
			(stroke
				(width 0.1)
				(type default)
			)
			(layer "F.Fab")
		)
		(fp_line
			(start -0.12065 0.3048)
			(end -0.67945 0.3048)
			(stroke
				(width 0.1)
				(type default)
			)
			(layer "F.Fab")
		)
		(fp_line
			(start 0.120396 0.3048)
			(end 0.120396 0.2794)
			(stroke
				(width 0.1)
				(type default)
			)
			(layer "F.Fab")
		)
		(fp_line
			(start 0.67945 0.3048)
			(end 0.120396 0.3048)
			(stroke
				(width 0.1)
				(type default)
			)
			(layer "F.Fab")
		)
		(fp_line
			(start -0.12065 0.2794)
			(end -0.12065 0.3048)
			(stroke
				(width 0.1)
				(type default)
			)
			(layer "F.Fab")
		)
		(fp_line
			(start 0.120396 0.2794)
			(end -0.12065 0.2794)
			(stroke
				(width 0.1)
				(type default)
			)
			(layer "F.Fab")
		)
		(fp_line
			(start -0.12065 -0.2794)
			(end 0.12065 -0.2794)
			(stroke
				(width 0.1)
				(type default)
			)
			(layer "F.Fab")
		)
		(fp_line
			(start 0.12065 -0.2794)
			(end 0.12065 -0.3048)
			(stroke
				(width 0.1)
				(type default)
			)
			(layer "F.Fab")
		)
		(fp_line
			(start 0.12065 -0.3048)
			(end 0.67945 -0.3048)
			(stroke
				(width 0.1)
				(type default)
			)
			(layer "F.Fab")
		)
		(fp_line
			(start 0.67945 -0.3048)
			(end 0.67945 0.3048)
			(stroke
				(width 0.1)
				(type default)
			)
			(layer "F.Fab")
		)
		(fp_line
			(start -0.67945 -0.305054)
			(end -0.12065 -0.305054)
			(stroke
				(width 0.1)
				(type default)
			)
			(layer "F.Fab")
		)
		(fp_line
			(start -0.12065 -0.305054)
			(end -0.12065 -0.2794)
			(stroke
				(width 0.1)
				(type default)
			)
			(layer "F.Fab")
		)
		(pad "1" smd circle
			(at -0.40005 0 270)
			(size 0 0)
			(layers "F.Cu" "F.Mask" "F.Paste")
			(net "FM_CPU0_SP5R4")
		)
		(pad "2" smd circle
			(at 0.40005 0 270)
			(size 0 0)
			(layers "F.Cu" "F.Mask" "F.Paste")
			(net "CPU0_SP5R4")
		)
	)
)
